(kicad_pcb
	(version 20241229)
	(generator "pcbnew")
	(generator_version "9.0")
	(general
		(thickness 1.61)
		(legacy_teardrops no)
	)
	(paper "A3")
	(title_block
		(title "RDIMM DDR5 Tester")
		(date "2026-05-21")
		(rev "2.2.0")
		(company "Antmicro")
		(comment 9 "footprints 41-43 of 796")
	)
	(layers
		(0 "F.Cu" signal)
		(4 "In1.Cu" power)
		(6 "In2.Cu" mixed)
		(8 "In3.Cu" power)
		(10 "In4.Cu" mixed)
		(12 "In5.Cu" power)
		(14 "In6.Cu" mixed)
		(16 "In7.Cu" power)
		(18 "In8.Cu" power)
		(20 "In9.Cu" mixed)
		(22 "In10.Cu" power)
		(2 "B.Cu" signal)
		(9 "F.Adhes" user "F.Adhesive")
		(11 "B.Adhes" user "B.Adhesive")
		(13 "F.Paste" user)
		(15 "B.Paste" user)
		(5 "F.SilkS" user "F.Silkscreen")
		(7 "B.SilkS" user "B.Silkscreen")
		(1 "F.Mask" user)
		(3 "B.Mask" user)
		(17 "Dwgs.User" user "User.Drawings")
		(19 "Cmts.User" user "User.Comments")
		(21 "Eco1.User" user "User.Eco1")
		(23 "Eco2.User" user "User.Eco2")
		(25 "Edge.Cuts" user)
		(27 "Margin" user)
		(31 "F.CrtYd" user "F.Courtyard")
		(29 "B.CrtYd" user "B.Courtyard")
		(35 "F.Fab" user)
		(33 "B.Fab" user)
	)
	(footprint "antmicro-footprints:HDMI-A_Receptacle_WE_685119134923"
		(layer "F.Cu")
		(at 104.145 179.215 90)
		(property "Reference" "J4"
			(at -9.16 6.88 0)
			(layer "F.SilkS")
			(effects
				(font
					(size 0.7 0.7)
					(thickness 0.15)
				)
				(justify right bottom)
			)
		)
		(property "Value" "HDMI-A_WE_685119134923"
			(at 0 7.8 90)
			(layer "F.Fab")
			(effects
				(font
					(size 0.7 0.7)
					(thickness 0.15)
				)
				(justify left bottom)
			)
		)
		(property "Datasheet" "https://www.we-online.com/components/products/datasheet/685119134923.pdf"
			(at 0 0 90)
			(layer "F.Fab")
			(hide yes)
			(effects
				(font
					(size 1.27 1.27)
					(thickness 0.15)
				)
			)
		)
		(property "MPN" "685119134923"
			(at 0 0 90)
			(unlocked yes)
			(layer "F.Fab")
			(hide yes)
			(effects
				(font
					(size 1 1)
					(thickness 0.15)
				)
			)
		)
		(property "Manufacturer" "Würth Elektronik"
			(at 0 0 90)
			(unlocked yes)
			(layer "F.Fab")
			(hide yes)
			(effects
				(font
					(size 1 1)
					(thickness 0.15)
				)
			)
		)
		(property "Author" "Antmicro"
			(at 0 0 90)
			(unlocked yes)
			(layer "F.Fab")
			(hide yes)
			(effects
				(font
					(size 1 1)
					(thickness 0.15)
				)
			)
		)
		(property "License" "Apache-2.0"
			(at 0 0 90)
			(unlocked yes)
			(layer "F.Fab")
			(hide yes)
			(effects
				(font
					(size 1 1)
					(thickness 0.15)
				)
			)
		)
		(property ki_fp_filters "685119134923")
		(sheetname "/HDMI + SD Card/")
		(sheetfile "hdmi-sd-card.kicad_sch")
		(attr smd)
		(fp_line
			(start -7.55 -0.125)
			(end -7.55 2.65)
			(stroke
				(width 0.12)
				(type solid)
			)
			(layer "F.SilkS")
		)
		(fp_line
			(start 7.55 2.75)
			(end 7.55 -0.15)
			(stroke
				(width 0.12)
				(type solid)
			)
			(layer "F.SilkS")
		)
		(fp_line
			(start 5.7 5.65)
			(end 4.75 5.65)
			(stroke
				(width 0.12)
				(type solid)
			)
			(layer "F.SilkS")
		)
		(fp_line
			(start -4.85 5.65)
			(end -5.8 5.65)
			(stroke
				(width 0.12)
				(type solid)
			)
			(layer "F.SilkS")
		)
		(fp_circle
			(center -4.9 5.9)
			(end -4.85 5.9)
			(stroke
				(width 0.15)
				(type solid)
			)
			(fill no)
			(layer "F.SilkS")
		)
		(fp_rect
			(start -8.05 -6.32)
			(end 7.949 6.78)
			(stroke
				(width 0.05)
				(type solid)
			)
			(fill no)
			(layer "F.CrtYd")
		)
		(fp_line
			(start -7.05 -5.616)
			(end 6.95 -5.616)
			(stroke
				(width 0.15)
				(type solid)
			)
			(layer "F.Fab")
		)
		(fp_line
			(start -7.05 5.525)
			(end -7.05 -5.616)
			(stroke
				(width 0.15)
				(type solid)
			)
			(layer "F.Fab")
		)
		(fp_line
			(start -7.05 5.525)
			(end -6.05 6.525)
			(stroke
				(width 0.15)
				(type solid)
			)
			(layer "F.Fab")
		)
		(fp_line
			(start 6.95 6.535)
			(end 6.95 -5.616)
			(stroke
				(width 0.15)
				(type solid)
			)
			(layer "F.Fab")
		)
		(fp_line
			(start 6.95 6.535)
			(end -6.05 6.535)
			(stroke
				(width 0.15)
				(type solid)
			)
			(layer "F.Fab")
		)
		(fp_text user "${REFERENCE}"
			(at -8 9.5 90)
			(layer "F.Fab")
			(effects
				(font
					(size 0.7 0.7)
					(thickness 0.15)
				)
				(justify left bottom)
			)
		)
		(fp_text user "License: Apache-2.0"
			(at -8 12.5 90)
			(layer "F.Fab")
			(effects
				(font
					(size 0.7 0.7)
					(thickness 0.15)
				)
				(justify left bottom)
			)
		)
		(fp_text user "Author: Antmicro"
			(at -8 11 90)
			(layer "F.Fab")
			(effects
				(font
					(size 0.7 0.7)
					(thickness 0.15)
				)
				(justify left bottom)
			)
		)
		(pad "1" smd rect
			(at -4.55 5.224 90)
			(size 0.28 2.6)
			(layers "F.Cu" "F.Mask" "F.Paste")
			(net 654 "/HDMI + SD Card/HDMI_OUT_CONN_D2_P")
			(pinfunction "D2+")
			(pintype "bidirectional")
		)
		(pad "2" smd rect
			(at -4.05 5.224 90)
			(size 0.28 2.6)
			(layers "F.Cu" "F.Mask" "F.Paste")
			(net 1 "GND")
			(pinfunction "D2S")
			(pintype "passive")
		)
		(pad "3" smd rect
			(at -3.551 5.224 90)
			(size 0.28 2.6)
			(layers "F.Cu" "F.Mask" "F.Paste")
			(net 655 "/HDMI + SD Card/HDMI_OUT_CONN_D2_N")
			(pinfunction "D2-")
			(pintype "bidirectional")
		)
		(pad "4" smd rect
			(at -3.051 5.224 90)
			(size 0.28 2.6)
			(layers "F.Cu" "F.Mask" "F.Paste")
			(net 656 "/HDMI + SD Card/HDMI_OUT_CONN_D1_P")
			(pinfunction "D1+")
			(pintype "bidirectional")
		)
		(pad "5" smd rect
			(at -2.551 5.224 90)
			(size 0.28 2.6)
			(layers "F.Cu" "F.Mask" "F.Paste")
			(net 1 "GND")
			(pinfunction "D1S")
			(pintype "passive")
		)
		(pad "6" smd rect
			(at -2.05 5.224 90)
			(size 0.28 2.6)
			(layers "F.Cu" "F.Mask" "F.Paste")
			(net 657 "/HDMI + SD Card/HDMI_OUT_CONN_D1_N")
			(pinfunction "D1-")
			(pintype "bidirectional")
		)
		(pad "7" smd rect
			(at -1.551 5.224 90)
			(size 0.28 2.6)
			(layers "F.Cu" "F.Mask" "F.Paste")
			(net 658 "/HDMI + SD Card/HDMI_OUT_CONN_D0_P")
			(pinfunction "D0+")
			(pintype "bidirectional")
		)
		(pad "8" smd rect
			(at -1.051 5.224 90)
			(size 0.28 2.6)
			(layers "F.Cu" "F.Mask" "F.Paste")
			(net 1 "GND")
			(pinfunction "D0S")
			(pintype "passive")
		)
		(pad "9" smd rect
			(at -0.551 5.224 90)
			(size 0.28 2.6)
			(layers "F.Cu" "F.Mask" "F.Paste")
			(net 659 "/HDMI + SD Card/HDMI_OUT_CONN_D0_N")
			(pinfunction "D0-")
			(pintype "bidirectional")
		)
		(pad "10" smd rect
			(at -0.051 5.224 90)
			(size 0.28 2.6)
			(layers "F.Cu" "F.Mask" "F.Paste")
			(net 660 "/HDMI + SD Card/HDMI_OUT_CONN_CLK_P")
			(pinfunction "CK+")
			(pintype "bidirectional")
		)
		(pad "11" smd rect
			(at 0.45 5.224 90)
			(size 0.28 2.6)
			(layers "F.Cu" "F.Mask" "F.Paste")
			(net 1 "GND")
			(pinfunction "CKS")
			(pintype "passive")
		)
		(pad "12" smd rect
			(at 0.95 5.224 90)
			(size 0.28 2.6)
			(layers "F.Cu" "F.Mask" "F.Paste")
			(net 661 "/HDMI + SD Card/HDMI_OUT_CONN_CLK_N")
			(pinfunction "CK-")
			(pintype "bidirectional")
		)
		(pad "13" smd rect
			(at 1.449 5.224 90)
			(size 0.28 2.6)
			(layers "F.Cu" "F.Mask" "F.Paste")
			(net 603 "unconnected-(J4-CEC-Pad13)")
			(pinfunction "CEC")
			(pintype "bidirectional+no_connect")
		)
		(pad "14" smd rect
			(at 1.949 5.224 90)
			(size 0.28 2.6)
			(layers "F.Cu" "F.Mask" "F.Paste")
			(net 247 "unconnected-(J4-UTILITY{slash}HEAC+-Pad14)")
			(pinfunction "UTILITY/HEAC+")
			(pintype "bidirectional+no_connect")
		)
		(pad "15" smd rect
			(at 2.45 5.224 90)
			(size 0.28 2.6)
			(layers "F.Cu" "F.Mask" "F.Paste")
			(net 467 "/HDMI + SD Card/HDMI_OUT_C.SCL")
			(pinfunction "SCL")
			(pintype "bidirectional")
		)
		(pad "16" smd rect
			(at 2.95 5.224 90)
			(size 0.28 2.6)
			(layers "F.Cu" "F.Mask" "F.Paste")
			(net 468 "/HDMI + SD Card/HDMI_OUT_C.SDA")
			(pinfunction "SDA")
			(pintype "bidirectional")
		)
		(pad "17" smd rect
			(at 3.45 5.224 90)
			(size 0.28 2.6)
			(layers "F.Cu" "F.Mask" "F.Paste")
			(net 1 "GND")
			(pinfunction "GND")
			(pintype "power_in")
		)
		(pad "18" smd rect
			(at 3.95 5.224 90)
			(size 0.28 2.6)
			(layers "F.Cu" "F.Mask" "F.Paste")
			(net 8 "/HDMI + SD Card/HDMI_CONN_5V")
			(pinfunction "+5V")
			(pintype "power_in")
		)
		(pad "19" smd rect
			(at 4.45 5.224 90)
			(size 0.28 2.6)
			(layers "F.Cu" "F.Mask" "F.Paste")
			(net 605 "/HDMI + SD Card/HDMI0.HPD")
			(pinfunction "HPD/HEAC-")
			(pintype "bidirectional")
		)
		(pad "SH" thru_hole oval
			(at -7.3 -1.577 90)
			(size 1.5 2.7)
			(drill oval 0.9 2.1)
			(layers "*.Cu" "*.Mask")
			(remove_unused_layers no)
			(net 188 "Net-(C132-Pad1)")
			(pinfunction "SH")
			(pintype "passive")
		)
		(pad "SH" thru_hole oval
			(at -7.3 4.424 90)
			(size 1.5 3.3)
			(drill oval 0.9 2.7)
			(layers "*.Cu" "*.Mask")
			(remove_unused_layers no)
			(net 188 "Net-(C132-Pad1)")
			(pinfunction "SH")
			(pintype "passive")
		)
		(pad "SH" thru_hole oval
			(at 7.2 -1.577 90)
			(size 1.5 2.7)
			(drill oval 0.9 2.1)
			(layers "*.Cu" "*.Mask")
			(remove_unused_layers no)
			(net 188 "Net-(C132-Pad1)")
			(pinfunction "SH")
			(pintype "passive")
		)
		(pad "SH" thru_hole oval
			(at 7.2 4.424 90)
			(size 1.5 3.3)
			(drill oval 0.9 2.7)
			(layers "*.Cu" "*.Mask")
			(remove_unused_layers no)
			(net 188 "Net-(C132-Pad1)")
			(pinfunction "SH")
			(pintype "passive")
		)
	)
	(footprint "antmicro-footprints:R_0402_1005Metric"
		(layer "F.Cu")
		(at 134.324499 166.449)
		(descr "Resistor SMD 0402")
		(tags "resistor SMD 0402")
		(property "Reference" "R43"
			(at 0.725501 1.451 0)
			(layer "F.SilkS")
			(effects
				(font
					(size 0.7 0.7)
					(thickness 0.15)
				)
				(justify left bottom)
			)
		)
		(property "Value" "R_10k_0402"
			(at -1.011843 1.772047 0)
			(layer "F.Fab")
			(effects
				(font
					(size 0.7 0.7)
					(thickness 0.15)
				)
				(justify left bottom)
			)
		)
		(property "Datasheet" "https://www.bourns.com/docs/product-datasheets/cr.pdf"
			(at 0 0 0)
			(layer "F.Fab")
			(hide yes)
			(effects
				(font
					(size 1.27 1.27)
					(thickness 0.15)
				)
			)
		)
		(property "Manufacturer" "Bourns"
			(at 0 0 0)
			(unlocked yes)
			(layer "F.Fab")
			(hide yes)
			(effects
				(font
					(size 1 1)
					(thickness 0.15)
				)
			)
		)
		(property "MPN" "CR0402-FX-1002GLF"
			(at 0 0 0)
			(unlocked yes)
			(layer "F.Fab")
			(hide yes)
			(effects
				(font
					(size 1 1)
					(thickness 0.15)
				)
			)
		)
		(property "Val" "10k"
			(at 0 0 0)
			(unlocked yes)
			(layer "F.Fab")
			(hide yes)
			(effects
				(font
					(size 1 1)
					(thickness 0.15)
				)
			)
		)
		(property "License" "Apache-2.0"
			(at 0 0 0)
			(unlocked yes)
			(layer "F.Fab")
			(hide yes)
			(effects
				(font
					(size 1 1)
					(thickness 0.15)
				)
			)
		)
		(property "Author" "Antmicro"
			(at 0 0 0)
			(unlocked yes)
			(layer "F.Fab")
			(hide yes)
			(effects
				(font
					(size 1 1)
					(thickness 0.15)
				)
			)
		)
		(property "Tolerance" "1%"
			(at 0 0 0)
			(unlocked yes)
			(layer "F.Fab")
			(hide yes)
			(effects
				(font
					(size 1 1)
					(thickness 0.15)
				)
			)
		)
		(sheetname "/Debug FTDI + VNA/")
		(sheetfile "debug-ftdi.kicad_sch")
		(attr smd)
		(fp_rect
			(start -0.925 -0.47)
			(end 0.925 0.47)
			(stroke
				(width 0.05)
				(type default)
			)
			(fill no)
			(layer "F.CrtYd")
		)
		(fp_rect
			(start -0.5 -0.25)
			(end 0.5 0.25)
			(stroke
				(width 0.15)
				(type solid)
			)
			(fill no)
			(layer "F.Fab")
		)
		(fp_text user "Author: Antmicro"
			(at -0.95 4.169 0)
			(layer "F.Fab")
			(effects
				(font
					(size 0.7 0.7)
					(thickness 0.15)
				)
				(justify left bottom)
			)
		)
		(fp_text user "${REFERENCE}"
			(at -0.95 3.168 0)
			(layer "F.Fab")
			(effects
				(font
					(size 0.7 0.7)
					(thickness 0.15)
				)
				(justify left bottom)
			)
		)
		(fp_text user "License: Apache-2.0"
			(at -0.95 5.169 0)
			(layer "F.Fab")
			(effects
				(font
					(size 0.7 0.7)
					(thickness 0.15)
				)
				(justify left bottom)
			)
		)
		(pad "1" smd roundrect
			(at -0.48 0)
			(size 0.59 0.64)
			(layers "F.Cu" "F.Mask" "F.Paste")
			(roundrect_rratio 0.25)
			(net 6 "/Debug FTDI + VNA/FTDI_3V3")
			(pintype "passive")
		)
		(pad "2" smd roundrect
			(at 0.48 0)
			(size 0.59 0.64)
			(layers "F.Cu" "F.Mask" "F.Paste")
			(roundrect_rratio 0.25)
			(net 289 "Net-(U6-~{RESET})")
			(pintype "passive")
		)
	)
	(footprint "antmicro-footprints:R_0402_1005Metric"
		(layer "F.Cu")
		(at 122.681 168.3125 90)
		(descr "Resistor SMD 0402")
		(tags "resistor SMD 0402")
		(property "Reference" "R221"
			(at -3.825 0.619 90)
			(layer "F.SilkS")
			(effects
				(font
					(size 0.7 0.7)
					(thickness 0.15)
				)
				(justify left bottom)
			)
		)
		(property "Value" "R_64k9_0402"
			(at -1.011843 1.772047 90)
			(layer "F.Fab")
			(effects
				(font
					(size 0.7 0.7)
					(thickness 0.15)
				)
				(justify left bottom)
			)
		)
		(property "Datasheet" "https://www.bourns.com/docs/product-datasheets/cr.pdf"
			(at 0 0 90)
			(layer "F.Fab")
			(hide yes)
			(effects
				(font
					(size 1.27 1.27)
					(thickness 0.15)
				)
			)
		)
		(property "MPN" "CR0402-FX-6492GLF"
			(at 0 0 90)
			(unlocked yes)
			(layer "F.Fab")
			(hide yes)
			(effects
				(font
					(size 1 1)
					(thickness 0.15)
				)
			)
		)
		(property "Manufacturer" "Bourns"
			(at 0 0 90)
			(unlocked yes)
			(layer "F.Fab")
			(hide yes)
			(effects
				(font
					(size 1 1)
					(thickness 0.15)
				)
			)
		)
		(property "License" "Apache-2.0"
			(at 0 0 90)
			(unlocked yes)
			(layer "F.Fab")
			(hide yes)
			(effects
				(font
					(size 1 1)
					(thickness 0.15)
				)
			)
		)
		(property "Author" "Antmicro"
			(at 0 0 90)
			(unlocked yes)
			(layer "F.Fab")
			(hide yes)
			(effects
				(font
					(size 1 1)
					(thickness 0.15)
				)
			)
		)
		(property "Val" "64k9"
			(at 0 0 90)
			(unlocked yes)
			(layer "F.Fab")
			(hide yes)
			(effects
				(font
					(size 1 1)
					(thickness 0.15)
				)
			)
		)
		(property "Tolerance" "1%"
			(at 0 0 90)
			(unlocked yes)
			(layer "F.Fab")
			(hide yes)
			(effects
				(font
					(size 1 1)
					(thickness 0.15)
				)
			)
		)
		(sheetname "/HDMI + SD Card/")
		(sheetfile "hdmi-sd-card.kicad_sch")
		(attr smd exclude_from_bom dnp)
		(fp_rect
			(start -0.925 -0.47)
			(end 0.925 0.47)
			(stroke
				(width 0.05)
				(type default)
			)
			(fill no)
			(layer "F.CrtYd")
		)
		(fp_rect
			(start -0.5 -0.25)
			(end 0.5 0.25)
			(stroke
				(width 0.15)
				(type solid)
			)
			(fill no)
			(layer "F.Fab")
		)
		(fp_text user "Author: Antmicro"
			(at -0.95 4.169 90)
			(layer "F.Fab")
			(effects
				(font
					(size 0.7 0.7)
					(thickness 0.15)
				)
				(justify left bottom)
			)
		)
		(fp_text user "License: Apache-2.0"
			(at -0.95 5.169 90)
			(layer "F.Fab")
			(effects
				(font
					(size 0.7 0.7)
					(thickness 0.15)
				)
				(justify left bottom)
			)
		)
		(fp_text user "${REFERENCE}"
			(at -0.95 3.168 90)
			(layer "F.Fab")
			(effects
				(font
					(size 0.7 0.7)
					(thickness 0.15)
				)
				(justify left bottom)
			)
		)
		(pad "1" smd roundrect
			(at -0.48 0 90)
			(size 0.59 0.64)
			(layers "F.Cu" "F.Mask" "F.Paste")
			(roundrect_rratio 0.25)
			(net 1 "GND")
			(pintype "passive")
		)
		(pad "2" smd roundrect
			(at 0.48 0 90)
			(size 0.59 0.64)
			(layers "F.Cu" "F.Mask" "F.Paste")
			(roundrect_rratio 0.25)
			(net 740 "/HDMI + SD Card/SLEW_CTL")
			(pintype "passive")
		)
	)
)
